FILE_TYPE=LIBRARY_PARTS;
primitive 'PCA9555APW';
  pin
    'VDD':
      PIN_NUMBER='(24)';
      PINUSE='POWER';
      NO_LOAD_CHECK='Both';
      NO_IO_CHECK='Both';
      NO_ASSERT_CHECK='TRUE';
      NO_DIR_CHECK='TRUE';
      ALLOW_CONNECT='TRUE';
    'VSS':
      PIN_NUMBER='(12)';
      PINUSE='POWER';
      NO_LOAD_CHECK='Both';
      NO_IO_CHECK='Both';
      NO_ASSERT_CHECK='TRUE';
      NO_DIR_CHECK='TRUE';
      ALLOW_CONNECT='TRUE';
    'INT#':
      PIN_NUMBER='(1)';
      OUTPUT_LOAD='(1.0,-1.0)';
    'SDA':
      PIN_NUMBER='(23)';
      BIDIRECTIONAL='TRUE';
      INPUT_LOAD='(-0.01,0.01)';
      OUTPUT_LOAD='(1.0,-1.0)';
    'SCL':
      PIN_NUMBER='(22)';
      INPUT_LOAD='(-0.01,0.01)';
    'P0_0':
      PIN_NUMBER='(4)';
      BIDIRECTIONAL='TRUE';
      INPUT_LOAD='(-0.01,0.01)';
      OUTPUT_LOAD='(1.0,-1.0)';
    'P0_1':
      PIN_NUMBER='(5)';
      BIDIRECTIONAL='TRUE';
      INPUT_LOAD='(-0.01,0.01)';
      OUTPUT_LOAD='(1.0,-1.0)';
    'P0_2':
      PIN_NUMBER='(6)';
      BIDIRECTIONAL='TRUE';
      INPUT_LOAD='(-0.01,0.01)';
      OUTPUT_LOAD='(1.0,-1.0)';
    'P0_3':
      PIN_NUMBER='(7)';
      BIDIRECTIONAL='TRUE';
      INPUT_LOAD='(-0.01,0.01)';
      OUTPUT_LOAD='(1.0,-1.0)';
    'P0_4':
      PIN_NUMBER='(8)';
      BIDIRECTIONAL='TRUE';
      INPUT_LOAD='(-0.01,0.01)';
      OUTPUT_LOAD='(1.0,-1.0)';
    'P0_5':
      PIN_NUMBER='(9)';
      BIDIRECTIONAL='TRUE';
      INPUT_LOAD='(-0.01,0.01)';
      OUTPUT_LOAD='(1.0,-1.0)';
    'P0_6':
      PIN_NUMBER='(10)';
      BIDIRECTIONAL='TRUE';
      INPUT_LOAD='(-0.01,0.01)';
      OUTPUT_LOAD='(1.0,-1.0)';
    'P0_7':
      PIN_NUMBER='(11)';
      BIDIRECTIONAL='TRUE';
      INPUT_LOAD='(-0.01,0.01)';
      OUTPUT_LOAD='(1.0,-1.0)';
    'P1_0':
      PIN_NUMBER='(13)';
      BIDIRECTIONAL='TRUE';
      INPUT_LOAD='(-0.01,0.01)';
      OUTPUT_LOAD='(1.0,-1.0)';
    'P1_1':
      PIN_NUMBER='(14)';
      BIDIRECTIONAL='TRUE';
      INPUT_LOAD='(-0.01,0.01)';
      OUTPUT_LOAD='(1.0,-1.0)';
    'P1_2':
      PIN_NUMBER='(15)';
      BIDIRECTIONAL='TRUE';
      INPUT_LOAD='(-0.01,0.01)';
      OUTPUT_LOAD='(1.0,-1.0)';
    'P1_3':
      PIN_NUMBER='(16)';
      BIDIRECTIONAL='TRUE';
      INPUT_LOAD='(-0.01,0.01)';
      OUTPUT_LOAD='(1.0,-1.0)';
    'P1_4':
      PIN_NUMBER='(17)';
      BIDIRECTIONAL='TRUE';
      INPUT_LOAD='(-0.01,0.01)';
      OUTPUT_LOAD='(1.0,-1.0)';
    'P1_5':
      PIN_NUMBER='(18)';
      BIDIRECTIONAL='TRUE';
      INPUT_LOAD='(-0.01,0.01)';
      OUTPUT_LOAD='(1.0,-1.0)';
    'P1_6':
      PIN_NUMBER='(19)';
      BIDIRECTIONAL='TRUE';
      INPUT_LOAD='(-0.01,0.01)';
      OUTPUT_LOAD='(1.0,-1.0)';
    'P1_7':
      PIN_NUMBER='(20)';
      BIDIRECTIONAL='TRUE';
      INPUT_LOAD='(-0.01,0.01)';
      OUTPUT_LOAD='(1.0,-1.0)';
    'A0':
      PIN_NUMBER='(21)';
      INPUT_LOAD='(-0.01,0.01)';
    'A1':
      PIN_NUMBER='(2)';
      INPUT_LOAD='(-0.01,0.01)';
    'A2':
      PIN_NUMBER='(3)';
      INPUT_LOAD='(-0.01,0.01)';
  end_pin;
  body
    PART_NAME='PCA9555APW';
    BODY_NAME='PCA9555APW';
    PHYS_DES_PREFIX='U';
    CLASS='IC';
  end_body;
end_primitive;

END.
